#ISCELL
  mstr_misc dns *
  *
#ISCELL
  pure_quanta quanta_title_block_c *
  *
#CELL
  pure_quanta zener_ac *
  page372_i1
#CELL
  pure_quanta q_res *
  page372_i10
#ISCELL
  pure_quanta_power gnd *
  page372_i100
#ISCELL
  standard offpage *
  page372_i101
#ISCELL
  standard offpage *
  page372_i102
#CELL
  pure_quanta conn3_210hp1030br1 *
  page372_i103
#CELL
  pure_quanta q_res *
  page372_i104
#CELL
  pure_quanta mosfet_nch_gds_esd_protected *
  page372_i11
#ISCELL
  pure_quanta_power gnd *
  page372_i12
#CELL
  pure_quanta q_res *
  page372_i13
#ISCELL
  pure_quanta_power gnd *
  page372_i14
#CELL
  pure_quanta q_res *
  page372_i16
#ISCELL
  pure_quanta_power gnd *
  page372_i17
#CELL
  pure_quanta conn3_210hp1030br1 *
  page372_i18
#CELL
  pure_quanta q_res *
  page372_i19
#ISCELL
  standard offpage *
  page372_i2
#ISCELL
  standard offpage *
  page372_i20
#CELL
  pure_quanta q_cap *
  page372_i22
#ISCELL
  standard offpage *
  page372_i23
#ISCELL
  pure_quanta_power universal_gnd *
  page372_i24
#ISCELL
  pure_quanta_power gnd *
  page372_i25
#ISCELL
  pure_quanta_power universal_gnd *
  page372_i26
#CELL
  pure_quanta q_res *
  page372_i27
#ISCELL
  pure_quanta_power universal_gnd *
  page372_i28
#CELL
  pure_quanta q_res *
  page372_i29
#CELL
  pure_quanta zener_ac *
  page372_i3
#CELL
  pure_quanta q_res *
  page372_i30
#ISCELL
  pure_quanta_power universal_power *
  page372_i31
#ISCELL
  pure_quanta_power universal_gnd *
  page372_i32
#CELL
  pure_quanta q_res *
  page372_i33
#CELL
  pure_quanta q_res *
  page372_i35
#ISCELL
  pure_quanta_power universal_power *
  page372_i36
#ISCELL
  pure_quanta_power universal_gnd *
  page372_i39
#ISCELL
  pure_quanta_power gnd *
  page372_i4
#ISCELL
  standard offpage *
  page372_i40
#ISCELL
  pure_quanta_power universal_gnd *
  page372_i41
#CELL
  pure_quanta mosfet_n *
  page372_i42
#CELL
  pure_quanta q_res *
  page372_i43
#ISCELL
  pure_quanta_power universal_power *
  page372_i44
#CELL
  pure_quanta q_res *
  page372_i45
#CELL
  pure_quanta q_res *
  page372_i46
#ISCELL
  pure_quanta_power universal_power *
  page372_i47
#ISCELL
  standard offpage *
  page372_i48
#CELL
  pure_quanta lt6700cs61trpbf *
  page372_i49
#ISCELL
  pure_quanta_power universal_power *
  page372_i5
#ISCELL
  pure_quanta_power universal_gnd *
  page372_i50
#CELL
  pure_quanta lm4040aim3x25nopb *
  page372_i51
#CELL
  pure_quanta q_res *
  page372_i52
#ISCELL
  pure_quanta_power universal_power *
  page372_i53
#ISCELL
  pure_quanta_power universal_gnd *
  page372_i54
#CELL
  pure_quanta q_res *
  page372_i55
#CELL
  pure_quanta q_res *
  page372_i56
#ISCELL
  pure_quanta_power universal_power *
  page372_i57
#ISCELL
  pure_quanta_power universal_gnd *
  page372_i58
#CELL
  pure_quanta q_cap *
  page372_i59
#CELL
  pure_quanta q_fuse *
  page372_i6
#ISCELL
  pure_quanta_power universal_gnd *
  page372_i60
#CELL
  pure_quanta q_cap *
  page372_i61
#ISCELL
  pure_quanta_power universal_gnd *
  page372_i62
#CELL
  pure_quanta q_res *
  page372_i63
#ISCELL
  pure_quanta_power universal_power *
  page372_i64
#ISCELL
  pure_quanta_power universal_gnd *
  page372_i65
#CELL
  pure_quanta q_cap *
  page372_i66
#CELL
  pure_quanta q_res *
  page372_i67
#ISCELL
  standard offpage *
  page372_i68
#CELL
  pure_quanta q_res *
  page372_i69
#ISCELL
  pure_quanta_power universal_gnd *
  page372_i7
#ISCELL
  pure_quanta_power universal_power *
  page372_i70
#CELL
  pure_quanta ap331awg7 *
  page372_i71
#CELL
  pure_quanta q_res *
  page372_i72
#ISCELL
  pure_quanta_power universal_power *
  page372_i73
#ISCELL
  pure_quanta_power universal_gnd *
  page372_i74
#CELL
  pure_quanta q_res *
  page372_i75
#CELL
  pure_quanta q_res *
  page372_i76
#ISCELL
  pure_quanta_power universal_power *
  page372_i77
#ISCELL
  pure_quanta_power universal_gnd *
  page372_i78
#CELL
  pure_quanta q_cap *
  page372_i79
#ISCELL
  standard offpage *
  page372_i8
#CELL
  pure_quanta ap331awg7 *
  page372_i80
#CELL
  pure_quanta q_res *
  page372_i81
#ISCELL
  pure_quanta_power universal_gnd *
  page372_i82
#ISCELL
  pure_quanta_power universal_power *
  page372_i83
#CELL
  pure_quanta q_cap *
  page372_i84
#CELL
  pure_quanta q_res *
  page372_i85
#ISCELL
  standard offpage *
  page372_i86
#ISCELL
  pure_quanta_power universal_power *
  page372_i88
#ISCELL
  pure_quanta_power universal_gnd *
  page372_i89
#CELL
  pure_quanta q_cap *
  page372_i9
#ISCELL
  pure_quanta_power universal_gnd *
  page372_i90
#ISCELL
  pure_quanta_power universal_gnd *
  page372_i91
#CELL
  pure_quanta q_cap *
  page372_i92
#CELL
  pure_quanta lm4040aim3x25nopb *
  page372_i93
#ISCELL
  pure_quanta_power universal_gnd *
  page372_i95
#CELL
  pure_quanta q_cap *
  page372_i96
#CELL
  pure_quanta q_res *
  page372_i97
#ISCELL
  pure_quanta_power universal_power *
  page372_i98
#CELL
  pure_quanta q_cap *
  page372_i99
